0.00800 T01
0.01000 T02
0.01200 T03
0.01400 T04
0.01417 T05
0.01456 T06
0.01600 T07
0.02000 T08
0.02913 T09
0.04200 T010
0.06200 T011
0.08300 T012
0.08600 T013
0.08700 T014
0.09400 T015
0.09700 T016
0.11900 T017
0.13800 T018
0.14600 T019
